# SCM (Grand Teton) — schematic netlist excerpt (pin names and nets, part order shuffled) for the footprints in the layout excerpt that follows; sources: Cadence DE-HDL packaged netlist, KiCad conversion of 12092022_DA0F0TMDCD0_F0T_Management_Board_D_brd_V3_OCP.brd

R21  Q_RES  10 1% CHIP  pkg 0402LF  page 15 : A = V_DACG_R ; B = V_DACG

U42  MC74VHC1G32DTT1G  IC  pkg SOT23-5_0-95_3X1-5  page 52
  IN_B  = PWRGD_P5V_AUX
  IN_A  = PWRGD_P1V8_AUX
  GND  = GND
  OUT_Y  = EN_P3V3
  VCC  = P3V3_LDO

(kicad_pcb
	(version 20260206)
	(generator "pcbnew")
	(generator_version "10.0")
	(general
		(thickness 1.6)
		(legacy_teardrops no)
	)
	(paper "A4")
	(title_block
		(title "12092022_DA0F0TMDCD0_F0T_Management_Board_D_brd_V3_OCP.brd")
		(comment 1 "Grand Teton / footprints 242-243 of 1440")
	)
	(layers
		(0 "F.Cu" signal "TOP")
		(4 "In1.Cu" signal "GND")
		(6 "In2.Cu" signal "IN1")
		(8 "In3.Cu" signal "GND1")
		(10 "In4.Cu" signal "IN2")
		(12 "In5.Cu" signal "VCC")
		(14 "In6.Cu" signal "VCC1")
		(16 "In7.Cu" signal "IN3")
		(18 "In8.Cu" signal "GND2")
		(20 "In9.Cu" signal "IN4")
		(22 "In10.Cu" signal "GND3")
		(2 "B.Cu" signal "BOTTOM")
		(9 "F.Adhes" user "F.Adhesive")
		(11 "B.Adhes" user "B.Adhesive")
		(13 "F.Paste" user "Package Geometry/Pastemask Top")
		(15 "B.Paste" user "Package Geometry/Pastemask Bottom")
		(5 "F.SilkS" user "Ref Des/Silkscreen Top")
		(7 "B.SilkS" user "Ref Des/Silkscreen Bottom")
		(1 "F.Mask" user "Board Geometry/Soldermask Top")
		(3 "B.Mask" user "Board Geometry/Soldermask Bottom")
		(17 "Dwgs.User" user "User.Drawings")
		(19 "Cmts.User" user "User.Comments")
		(21 "Eco1.User" user "User.Eco1")
		(23 "Eco2.User" user "User.Eco2")
		(25 "Edge.Cuts" user "Board Geometry/Outline")
		(27 "Margin" user)
		(31 "F.CrtYd" user "Package Geometry/Place Bound Top")
		(29 "B.CrtYd" user "Package Geometry/Place Bound Bottom")
		(35 "F.Fab" user "Ref Des/Assembly Top")
		(33 "B.Fab" user "Ref Des/Assembly Bottom")
	)
	(footprint ""
		(layer "F.Cu")
		(at 13.081 -58.6232 90)
		(property "Reference" "U42"
			(at -2.49047 2.6416 0)
			(unlocked yes)
			(layer "F.SilkS")
			(effects
				(font
					(size 0.7874 0.5842)
					(thickness 0.1524)
				)
			)
		)
		(property "Value" ""
			(at 0 0 90)
			(layer "F.Fab")
			(effects
				(font
					(size 1.27 1.27)
				)
			)
		)
		(duplicate_pad_numbers_are_jumpers no)
		(fp_line
			(start 1.834896 -1.575054)
			(end 1.834896 1.575054)
			(stroke
				(width 0.1524)
				(type default)
			)
			(layer "F.SilkS")
		)
		(fp_line
			(start 0.508 -1.575054)
			(end 1.834896 -1.575054)
			(stroke
				(width 0.1524)
				(type default)
			)
			(layer "F.SilkS")
		)
		(fp_line
			(start -0.508 -1.575054)
			(end 0 -1.016)
			(stroke
				(width 0.1524)
				(type default)
			)
			(layer "F.SilkS")
		)
		(fp_line
			(start -1.834896 -1.575054)
			(end -0.508 -1.575054)
			(stroke
				(width 0.1524)
				(type default)
			)
			(layer "F.SilkS")
		)
		(fp_line
			(start 0 -1.016)
			(end 0.508 -1.575054)
			(stroke
				(width 0.1524)
				(type default)
			)
			(layer "F.SilkS")
		)
		(fp_line
			(start 1.834896 1.575054)
			(end -1.834896 1.575054)
			(stroke
				(width 0.1524)
				(type default)
			)
			(layer "F.SilkS")
		)
		(fp_line
			(start -1.834896 1.575054)
			(end -1.834896 -1.575054)
			(stroke
				(width 0.1524)
				(type default)
			)
			(layer "F.SilkS")
		)
		(fp_poly
			(pts
				(xy -3.003296 -1.45796) (xy -3.003296 -0.44196) (xy -1.987296 -0.94996)
			)
			(stroke
				(width 0)
				(type default)
			)
			(fill yes)
			(layer "F.SilkS")
		)
		(fp_line
			(start 0.824992 -1.575054)
			(end 0.824992 1.575054)
			(stroke
				(width 0.1)
				(type default)
			)
			(layer "F.Fab")
		)
		(fp_line
			(start -0.824992 -1.575054)
			(end 0.824992 -1.575054)
			(stroke
				(width 0.1)
				(type default)
			)
			(layer "F.Fab")
		)
		(fp_line
			(start 0.824992 1.575054)
			(end -0.824992 1.575054)
			(stroke
				(width 0.1)
				(type default)
			)
			(layer "F.Fab")
		)
		(fp_line
			(start -0.824992 1.575054)
			(end -0.824992 -1.575054)
			(stroke
				(width 0.1)
				(type default)
			)
			(layer "F.Fab")
		)
		(fp_poly
			(pts
				(xy -3.003296 -1.45796) (xy -3.003296 -0.44196) (xy -1.987296 -0.94996)
			)
			(stroke
				(width 0)
				(type default)
			)
			(fill yes)
			(layer "F.Fab")
		)
		(pad "1" smd rect
			(at -1.199896 -0.94996)
			(size 0.7112 1.016)
			(layers "F.Cu" "F.Mask" "F.Paste")
			(net "PWRGD_P5V_AUX")
		)
		(pad "2" smd rect
			(at -1.199896 0)
			(size 0.7112 1.016)
			(layers "F.Cu" "F.Mask" "F.Paste")
			(net "PWRGD_P1V8_AUX")
		)
		(pad "3" smd rect
			(at -1.199896 0.94996)
			(size 0.7112 1.016)
			(layers "F.Cu" "F.Mask" "F.Paste")
			(net "GND")
		)
		(pad "4" smd rect
			(at 1.199896 0.94996)
			(size 0.7112 1.016)
			(layers "F.Cu" "F.Mask" "F.Paste")
			(net "EN_P3V3")
		)
		(pad "5" smd rect
			(at 1.199896 -0.94996)
			(size 0.7112 1.016)
			(layers "F.Cu" "F.Mask" "F.Paste")
			(net "P3V3_LDO")
		)
	)
	(footprint ""
		(layer "F.Cu")
		(at 45.256196 -65.918334 90)
		(property "Reference" "R21"
			(at 0 0 90)
			(layer "F.SilkS")
			(hide yes)
			(effects
				(font
					(size 1.27 1.27)
				)
			)
		)
		(property "Value" ""
			(at 0 0 90)
			(layer "F.Fab")
			(effects
				(font
					(size 1.27 1.27)
				)
			)
		)
		(duplicate_pad_numbers_are_jumpers no)
		(fp_line
			(start 0.7874 -0.4064)
			(end 0.7874 0.4064)
			(stroke
				(width 0.1524)
				(type default)
			)
			(layer "F.SilkS")
		)
		(fp_line
			(start -0.7874 -0.4064)
			(end 0.7874 -0.4064)
			(stroke
				(width 0.1524)
				(type default)
			)
			(layer "F.SilkS")
		)
		(fp_line
			(start 0.7874 0.4064)
			(end -0.7874 0.4064)
			(stroke
				(width 0.1524)
				(type default)
			)
			(layer "F.SilkS")
		)
		(fp_line
			(start -0.7874 0.4064)
			(end -0.7874 -0.4064)
			(stroke
				(width 0.1524)
				(type default)
			)
			(layer "F.SilkS")
		)
		(fp_line
			(start -0.12065 -0.305054)
			(end -0.12065 -0.2794)
			(stroke
				(width 0.1)
				(type default)
			)
			(layer "F.Fab")
		)
		(fp_line
			(start -0.67945 -0.305054)
			(end -0.12065 -0.305054)
			(stroke
				(width 0.1)
				(type default)
			)
			(layer "F.Fab")
		)
		(fp_line
			(start 0.67945 -0.3048)
			(end 0.67945 0.3048)
			(stroke
				(width 0.1)
				(type default)
			)
			(layer "F.Fab")
		)
		(fp_line
			(start 0.12065 -0.3048)
			(end 0.67945 -0.3048)
			(stroke
				(width 0.1)
				(type default)
			)
			(layer "F.Fab")
		)
		(fp_line
			(start 0.12065 -0.2794)
			(end 0.12065 -0.3048)
			(stroke
				(width 0.1)
				(type default)
			)
			(layer "F.Fab")
		)
		(fp_line
			(start -0.12065 -0.2794)
			(end 0.12065 -0.2794)
			(stroke
				(width 0.1)
				(type default)
			)
			(layer "F.Fab")
		)
		(fp_line
			(start 0.120396 0.2794)
			(end -0.12065 0.2794)
			(stroke
				(width 0.1)
				(type default)
			)
			(layer "F.Fab")
		)
		(fp_line
			(start -0.12065 0.2794)
			(end -0.12065 0.3048)
			(stroke
				(width 0.1)
				(type default)
			)
			(layer "F.Fab")
		)
		(fp_line
			(start 0.67945 0.3048)
			(end 0.120396 0.3048)
			(stroke
				(width 0.1)
				(type default)
			)
			(layer "F.Fab")
		)
		(fp_line
			(start 0.120396 0.3048)
			(end 0.120396 0.2794)
			(stroke
				(width 0.1)
				(type default)
			)
			(layer "F.Fab")
		)
		(fp_line
			(start -0.12065 0.3048)
			(end -0.67945 0.3048)
			(stroke
				(width 0.1)
				(type default)
			)
			(layer "F.Fab")
		)
		(fp_line
			(start -0.67945 0.3048)
			(end -0.67945 -0.305054)
			(stroke
				(width 0.1)
				(type default)
			)
			(layer "F.Fab")
		)
		(pad "1" smd circle
			(at -0.40005 0 90)
			(size 0 0)
			(layers "F.Cu" "F.Mask" "F.Paste")
			(net "V_DACG_R")
		)
		(pad "2" smd circle
			(at 0.40005 0 90)
			(size 0 0)
			(layers "F.Cu" "F.Mask" "F.Paste")
			(net "V_DACG")
		)
	)
)
